(kicad_pcb
	(version 20260206)
	(generator "pcbnew")
	(generator_version "10.0")
	(general
		(thickness 1.6)
		(legacy_teardrops no)
	)
	(paper "A4")
	(title_block
		(title "Bryce Canyon_IOM_IOC_16318-2_OCP.brd")
		(comment 1 "Bryce Canyon / footprint 592 of 1605 (U1), pads 235-347 of 896")
	)
	(layers
		(0 "F.Cu" signal "TOP")
		(4 "In1.Cu" signal "L2GND")
		(6 "In2.Cu" signal "L3")
		(8 "In3.Cu" signal "L4VCC")
		(10 "In4.Cu" signal "L5VCC")
		(12 "In5.Cu" signal "L6")
		(14 "In6.Cu" signal "L7GND")
		(2 "B.Cu" signal "BOTTOM")
		(9 "F.Adhes" user "F.Adhesive")
		(11 "B.Adhes" user "B.Adhesive")
		(13 "F.Paste" user "Package Geometry/Pastemask Top")
		(15 "B.Paste" user "Package Geometry/Pastemask Bottom")
		(5 "F.SilkS" user "Ref Des/Silkscreen Top")
		(7 "B.SilkS" user "Ref Des/Silkscreen Bottom")
		(1 "F.Mask" user "Board Geometry/Soldermask Top")
		(3 "B.Mask" user "Board Geometry/Soldermask Bottom")
		(17 "Dwgs.User" user "User.Drawings")
		(19 "Cmts.User" user "User.Comments")
		(21 "Eco1.User" user "User.Eco1")
		(23 "Eco2.User" user "User.Eco2")
		(25 "Edge.Cuts" user "Board Geometry/Outline")
		(27 "Margin" user)
		(31 "F.CrtYd" user "Package Geometry/Place Bound Top")
		(29 "B.CrtYd" user "Package Geometry/Place Bound Bottom")
		(35 "F.Fab" user "Ref Des/Assembly Top")
		(33 "B.Fab" user "Ref Des/Assembly Bottom")
	)
	(footprint ""
		(layer "F.Cu")
		(at 192.79997 -65.099946 180)
		(property "Reference" "U1"
			(at 0 0 180)
			(layer "F.SilkS")
			(hide yes)
			(effects
				(font
					(size 1.27 1.27)
				)
			)
		)
		(property "Value" "SAS3008C0-1-DB-500020657-1-GP"
			(at -20.374102 -5.0292 180)
			(unlocked yes)
			(layer "F.Fab")
			(hide yes)
			(effects
				(font
					(size 1.016 1.016)
					(thickness 0.1524)
				)
			)
		)
		(property "Device Type" "BGA896D25H78"
			(at -20.374102 -6.5532 180)
			(unlocked yes)
			(layer "F.Fab")
			(hide yes)
			(effects
				(font
					(size 1.016 1.016)
					(thickness 0.1524)
				)
			)
		)
		(duplicate_pad_numbers_are_jumpers no)
		(pad "AG27" smd circle
			(at 9.19988 9.19988 180)
			(size 0.3556 0.3556)
			(layers "F.Cu" "F.Mask" "F.Paste")
			(net "P1V8")
		)
		(pad "AG28" smd circle
			(at 9.99998 9.19988 180)
			(size 0.3556 0.3556)
			(layers "F.Cu" "F.Mask" "F.Paste")
			(net "IOC_GPIO_25")
		)
		(pad "AG29" smd circle
			(at 10.80008 9.19988 180)
			(size 0.3556 0.3556)
			(layers "F.Cu" "F.Mask" "F.Paste")
			(net "IOC_GPIO_18")
		)
		(pad "AG30" smd circle
			(at 11.599926 9.19988 180)
			(size 0.3556 0.3556)
			(layers "F.Cu" "F.Mask" "F.Paste")
			(net "IOC_GPIO_21")
		)
		(pad "AH1" smd circle
			(at -11.599926 9.99998 180)
			(size 0.4064 0.4064)
			(layers "F.Cu" "F.Mask" "F.Paste")
			(net "PHY_IOC_TO_CON_A_0_DP_C")
		)
		(pad "AH2" smd circle
			(at -10.80008 9.99998 180)
			(size 0.4064 0.4064)
			(layers "F.Cu" "F.Mask" "F.Paste")
			(net "PHY_IOC_TO_CON_A_0_DN_C")
		)
		(pad "AH3" smd circle
			(at -9.99998 9.99998 180)
			(size 0.4064 0.4064)
			(layers "F.Cu" "F.Mask" "F.Paste")
			(net "GND")
		)
		(pad "AH4" smd circle
			(at -9.19988 9.99998 180)
			(size 0.3556 0.3556)
			(layers "F.Cu" "F.Mask" "F.Paste")
			(net "PHY_CON_A_TO_IOC_0_DP")
		)
		(pad "AH5" smd circle
			(at -8.400034 9.99998 180)
			(size 0.3556 0.3556)
			(layers "F.Cu" "F.Mask" "F.Paste")
			(net "PHY_CON_A_TO_IOC_0_DN")
		)
		(pad "AH6" smd circle
			(at -7.599934 9.99998 180)
			(size 0.3556 0.3556)
			(layers "F.Cu" "F.Mask" "F.Paste")
			(net "GND")
		)
		(pad "AH7" smd circle
			(at -6.800088 9.99998 180)
			(size 0.3556 0.3556)
			(layers "F.Cu" "F.Mask" "F.Paste")
			(net "GND")
		)
		(pad "AH8" smd circle
			(at -5.999988 9.99998 180)
			(size 0.3556 0.3556)
			(layers "F.Cu" "F.Mask" "F.Paste")
			(net "GND")
		)
		(pad "AH9" smd circle
			(at -5.199888 9.99998 180)
			(size 0.3556 0.3556)
			(layers "F.Cu" "F.Mask" "F.Paste")
			(net "GND")
		)
		(pad "AH10" smd circle
			(at -4.400042 9.99998 180)
			(size 0.3556 0.3556)
			(layers "F.Cu" "F.Mask" "F.Paste")
			(net "GND")
		)
		(pad "AH11" smd circle
			(at -3.599942 9.99998 180)
			(size 0.3556 0.3556)
			(layers "F.Cu" "F.Mask" "F.Paste")
			(net "GND")
		)
		(pad "AH12" smd circle
			(at -2.800096 9.99998 180)
			(size 0.3556 0.3556)
			(layers "F.Cu" "F.Mask" "F.Paste")
			(net "GND")
		)
		(pad "AH13" smd circle
			(at -1.999996 9.99998 180)
			(size 0.3556 0.3556)
			(layers "F.Cu" "F.Mask" "F.Paste")
			(net "GND")
		)
		(pad "AH14" smd circle
			(at -1.199896 9.99998 180)
			(size 0.3556 0.3556)
			(layers "F.Cu" "F.Mask" "F.Paste")
			(net "GND")
		)
		(pad "AH15" smd circle
			(at -0.40005 9.99998 180)
			(size 0.3556 0.3556)
			(layers "F.Cu" "F.Mask" "F.Paste")
			(net "PCE_VDDH")
		)
		(pad "AH16" smd circle
			(at 0.40005 9.99998 180)
			(size 0.3556 0.3556)
			(layers "F.Cu" "F.Mask" "F.Paste")
			(net "GND")
		)
		(pad "AH17" smd circle
			(at 1.199896 9.99998 180)
			(size 0.3556 0.3556)
			(layers "F.Cu" "F.Mask" "F.Paste")
			(net "GND")
		)
		(pad "AH18" smd circle
			(at 1.999996 9.99998 180)
			(size 0.3556 0.3556)
			(layers "F.Cu" "F.Mask" "F.Paste")
			(net "GND")
		)
		(pad "AH19" smd circle
			(at 2.800096 9.99998 180)
			(size 0.3556 0.3556)
			(layers "F.Cu" "F.Mask" "F.Paste")
			(net "Net_1208")
		)
		(pad "AH20" smd circle
			(at 3.599942 9.99998 180)
			(size 0.3556 0.3556)
			(layers "F.Cu" "F.Mask" "F.Paste")
			(net "SYS_RST_N_0")
		)
		(pad "AH21" smd circle
			(at 4.400042 9.99998 180)
			(size 0.3556 0.3556)
			(layers "F.Cu" "F.Mask" "F.Paste")
			(net "IOC_UART_1_TX")
		)
		(pad "AH22" smd circle
			(at 5.199888 9.99998 180)
			(size 0.3556 0.3556)
			(layers "F.Cu" "F.Mask" "F.Paste")
			(net "IOC_GPIO_2")
		)
		(pad "AH23" smd circle
			(at 5.999988 9.99998 180)
			(size 0.3556 0.3556)
			(layers "F.Cu" "F.Mask" "F.Paste")
			(net "IOC_GPIO_3")
		)
		(pad "AH24" smd circle
			(at 6.800088 9.99998 180)
			(size 0.3556 0.3556)
			(layers "F.Cu" "F.Mask" "F.Paste")
			(net "IOC_GPIO_5")
		)
		(pad "AH25" smd circle
			(at 7.599934 9.99998 180)
			(size 0.3556 0.3556)
			(layers "F.Cu" "F.Mask" "F.Paste")
			(net "IOC_GPIO_6")
		)
		(pad "AH26" smd circle
			(at 8.400034 9.99998 180)
			(size 0.3556 0.3556)
			(layers "F.Cu" "F.Mask" "F.Paste")
			(net "IOC_UART_1_RX")
		)
		(pad "AH27" smd circle
			(at 9.19988 9.99998 180)
			(size 0.3556 0.3556)
			(layers "F.Cu" "F.Mask" "F.Paste")
			(net "SPARE0")
		)
		(pad "AH28" smd circle
			(at 9.99998 9.99998 180)
			(size 0.4064 0.4064)
			(layers "F.Cu" "F.Mask" "F.Paste")
			(net "IOC_GPIO_10")
		)
		(pad "AH29" smd circle
			(at 10.80008 9.99998 180)
			(size 0.4064 0.4064)
			(layers "F.Cu" "F.Mask" "F.Paste")
			(net "IOC_GPIO_22")
		)
		(pad "AH30" smd circle
			(at 11.599926 9.99998 180)
			(size 0.4064 0.4064)
			(layers "F.Cu" "F.Mask" "F.Paste")
			(net "IOC_GPIO_11")
		)
		(pad "AJ1" smd circle
			(at -11.599926 10.80008 180)
			(size 0.4064 0.4064)
			(layers "F.Cu" "F.Mask" "F.Paste")
			(net "SAS0_VDDH")
		)
		(pad "AJ2" smd circle
			(at -10.80008 10.80008 180)
			(size 0.4064 0.4064)
			(layers "F.Cu" "F.Mask" "F.Paste")
			(net "GND")
		)
		(pad "AJ3" smd circle
			(at -9.99998 10.80008 180)
			(size 0.4064 0.4064)
			(layers "F.Cu" "F.Mask" "F.Paste")
			(net "SAS0_AVDD")
		)
		(pad "AJ4" smd circle
			(at -9.19988 10.80008 180)
			(size 0.3556 0.3556)
			(layers "F.Cu" "F.Mask" "F.Paste")
			(net "GND")
		)
		(pad "AJ5" smd circle
			(at -8.400034 10.80008 180)
			(size 0.3556 0.3556)
			(layers "F.Cu" "F.Mask" "F.Paste")
			(net "GND")
		)
		(pad "AJ6" smd circle
			(at -7.599934 10.80008 180)
			(size 0.3556 0.3556)
			(layers "F.Cu" "F.Mask" "F.Paste")
			(net "GND")
		)
		(pad "AJ7" smd circle
			(at -6.800088 10.80008 180)
			(size 0.3556 0.3556)
			(layers "F.Cu" "F.Mask" "F.Paste")
			(net "PCIE_COMP_TO_IOM_8_DN")
		)
		(pad "AJ8" smd circle
			(at -5.999988 10.80008 180)
			(size 0.3556 0.3556)
			(layers "F.Cu" "F.Mask" "F.Paste")
			(net "PCIE_COMP_TO_IOM_9_DN")
		)
		(pad "AJ9" smd circle
			(at -5.199888 10.80008 180)
			(size 0.3556 0.3556)
			(layers "F.Cu" "F.Mask" "F.Paste")
			(net "GND")
		)
		(pad "AJ10" smd circle
			(at -4.400042 10.80008 180)
			(size 0.3556 0.3556)
			(layers "F.Cu" "F.Mask" "F.Paste")
			(net "PCIE_COMP_TO_IOM_10_DN")
		)
		(pad "AJ11" smd circle
			(at -3.599942 10.80008 180)
			(size 0.3556 0.3556)
			(layers "F.Cu" "F.Mask" "F.Paste")
			(net "PCIE_COMP_TO_IOM_11_DN")
		)
		(pad "AJ12" smd circle
			(at -2.800096 10.80008 180)
			(size 0.3556 0.3556)
			(layers "F.Cu" "F.Mask" "F.Paste")
			(net "GND")
		)
		(pad "AJ13" smd circle
			(at -1.999996 10.80008 180)
			(size 0.3556 0.3556)
			(layers "F.Cu" "F.Mask" "F.Paste")
			(net "PCIE_COMP_TO_IOM_12_DN")
		)
		(pad "AJ14" smd circle
			(at -1.199896 10.80008 180)
			(size 0.3556 0.3556)
			(layers "F.Cu" "F.Mask" "F.Paste")
			(net "PCIE_COMP_TO_IOM_13_DN")
		)
		(pad "AJ15" smd circle
			(at -0.40005 10.80008 180)
			(size 0.3556 0.3556)
			(layers "F.Cu" "F.Mask" "F.Paste")
			(net "GND")
		)
		(pad "AJ16" smd circle
			(at 0.40005 10.80008 180)
			(size 0.3556 0.3556)
			(layers "F.Cu" "F.Mask" "F.Paste")
			(net "PCIE_COMP_TO_IOM_14_DN")
		)
		(pad "AJ17" smd circle
			(at 1.199896 10.80008 180)
			(size 0.3556 0.3556)
			(layers "F.Cu" "F.Mask" "F.Paste")
			(net "PCIE_COMP_TO_IOM_15_DN")
		)
		(pad "AJ18" smd circle
			(at 1.999996 10.80008 180)
			(size 0.3556 0.3556)
			(layers "F.Cu" "F.Mask" "F.Paste")
			(net "GND")
		)
		(pad "AJ19" smd circle
			(at 2.800096 10.80008 180)
			(size 0.3556 0.3556)
			(layers "F.Cu" "F.Mask" "F.Paste")
			(net "Net_1209")
		)
		(pad "AJ20" smd circle
			(at 3.599942 10.80008 180)
			(size 0.3556 0.3556)
			(layers "F.Cu" "F.Mask" "F.Paste")
			(net "SYS_ERR_0")
		)
		(pad "AJ21" smd circle
			(at 4.400042 10.80008 180)
			(size 0.3556 0.3556)
			(layers "F.Cu" "F.Mask" "F.Paste")
			(net "IOC_RESET#")
		)
		(pad "AJ22" smd circle
			(at 5.199888 10.80008 180)
			(size 0.3556 0.3556)
			(layers "F.Cu" "F.Mask" "F.Paste")
			(net "SPARE2")
		)
		(pad "AJ23" smd circle
			(at 5.999988 10.80008 180)
			(size 0.3556 0.3556)
			(layers "F.Cu" "F.Mask" "F.Paste")
			(net "SYS_DBMODE3")
		)
		(pad "AJ24" smd circle
			(at 6.800088 10.80008 180)
			(size 0.3556 0.3556)
			(layers "F.Cu" "F.Mask" "F.Paste")
			(net "IOC_UART_0_RX")
		)
		(pad "AJ25" smd circle
			(at 7.599934 10.80008 180)
			(size 0.3556 0.3556)
			(layers "F.Cu" "F.Mask" "F.Paste")
			(net "IOC_GPIO_13")
		)
		(pad "AJ26" smd circle
			(at 8.400034 10.80008 180)
			(size 0.3556 0.3556)
			(layers "F.Cu" "F.Mask" "F.Paste")
			(net "IOC_GPIO_1")
		)
		(pad "AJ27" smd circle
			(at 9.19988 10.80008 180)
			(size 0.3556 0.3556)
			(layers "F.Cu" "F.Mask" "F.Paste")
			(net "IOC_GPIO_14")
		)
		(pad "AJ28" smd circle
			(at 9.99998 10.80008 180)
			(size 0.4064 0.4064)
			(layers "F.Cu" "F.Mask" "F.Paste")
			(net "IOC_GPIO_20")
		)
		(pad "AJ29" smd circle
			(at 10.80008 10.80008 180)
			(size 0.4064 0.4064)
			(layers "F.Cu" "F.Mask" "F.Paste")
			(net "IOC_GPIO_12")
		)
		(pad "AJ30" smd circle
			(at 11.599926 10.80008 180)
			(size 0.4064 0.4064)
			(layers "F.Cu" "F.Mask" "F.Paste")
			(net "IOC_GPIO_4")
		)
		(pad "AK2" smd circle
			(at -10.80008 11.599926 180)
			(size 0.4064 0.4064)
			(layers "F.Cu" "F.Mask" "F.Paste")
			(net "GND")
		)
		(pad "AK3" smd circle
			(at -9.99998 11.599926 180)
			(size 0.4064 0.4064)
			(layers "F.Cu" "F.Mask" "F.Paste")
			(net "GND")
		)
		(pad "AK4" smd circle
			(at -9.19988 11.599926 180)
			(size 0.3556 0.3556)
			(layers "F.Cu" "F.Mask" "F.Paste")
			(net "PCIE_COMP_TO_IOM_CLK_2_DP")
		)
		(pad "AK5" smd circle
			(at -8.400034 11.599926 180)
			(size 0.3556 0.3556)
			(layers "F.Cu" "F.Mask" "F.Paste")
			(net "PCIE_COMP_TO_IOM_CLK_2_DN")
		)
		(pad "AK6" smd circle
			(at -7.599934 11.599926 180)
			(size 0.3556 0.3556)
			(layers "F.Cu" "F.Mask" "F.Paste")
			(net "PCE_AVDD")
		)
		(pad "AK7" smd circle
			(at -6.800088 11.599926 180)
			(size 0.3556 0.3556)
			(layers "F.Cu" "F.Mask" "F.Paste")
			(net "PCIE_COMP_TO_IOM_8_DP")
		)
		(pad "AK8" smd circle
			(at -5.999988 11.599926 180)
			(size 0.3556 0.3556)
			(layers "F.Cu" "F.Mask" "F.Paste")
			(net "PCIE_COMP_TO_IOM_9_DP")
		)
		(pad "AK9" smd circle
			(at -5.199888 11.599926 180)
			(size 0.3556 0.3556)
			(layers "F.Cu" "F.Mask" "F.Paste")
			(net "PCE_AVDD")
		)
		(pad "AK10" smd circle
			(at -4.400042 11.599926 180)
			(size 0.3556 0.3556)
			(layers "F.Cu" "F.Mask" "F.Paste")
			(net "PCIE_COMP_TO_IOM_10_DP")
		)
		(pad "AK11" smd circle
			(at -3.599942 11.599926 180)
			(size 0.3556 0.3556)
			(layers "F.Cu" "F.Mask" "F.Paste")
			(net "PCIE_COMP_TO_IOM_11_DP")
		)
		(pad "AK12" smd circle
			(at -2.800096 11.599926 180)
			(size 0.3556 0.3556)
			(layers "F.Cu" "F.Mask" "F.Paste")
			(net "PCE_AVDD")
		)
		(pad "AK13" smd circle
			(at -1.999996 11.599926 180)
			(size 0.3556 0.3556)
			(layers "F.Cu" "F.Mask" "F.Paste")
			(net "PCIE_COMP_TO_IOM_12_DP")
		)
		(pad "AK14" smd circle
			(at -1.199896 11.599926 180)
			(size 0.3556 0.3556)
			(layers "F.Cu" "F.Mask" "F.Paste")
			(net "PCIE_COMP_TO_IOM_13_DP")
		)
		(pad "AK15" smd circle
			(at -0.40005 11.599926 180)
			(size 0.3556 0.3556)
			(layers "F.Cu" "F.Mask" "F.Paste")
			(net "PCE_AVDD")
		)
		(pad "AK16" smd circle
			(at 0.40005 11.599926 180)
			(size 0.3556 0.3556)
			(layers "F.Cu" "F.Mask" "F.Paste")
			(net "PCIE_COMP_TO_IOM_14_DP")
		)
		(pad "AK17" smd circle
			(at 1.199896 11.599926 180)
			(size 0.3556 0.3556)
			(layers "F.Cu" "F.Mask" "F.Paste")
			(net "PCIE_COMP_TO_IOM_15_DP")
		)
		(pad "AK18" smd circle
			(at 1.999996 11.599926 180)
			(size 0.3556 0.3556)
			(layers "F.Cu" "F.Mask" "F.Paste")
			(net "PCE_AVDD")
		)
		(pad "AK19" smd circle
			(at 2.800096 11.599926 180)
			(size 0.3556 0.3556)
			(layers "F.Cu" "F.Mask" "F.Paste")
			(net "Net_1210")
		)
		(pad "AK20" smd circle
			(at 3.599942 11.599926 180)
			(size 0.3556 0.3556)
			(layers "F.Cu" "F.Mask" "F.Paste")
			(net "SYS_DBMODE1")
		)
		(pad "AK21" smd circle
			(at 4.400042 11.599926 180)
			(size 0.3556 0.3556)
			(layers "F.Cu" "F.Mask" "F.Paste")
			(net "SYS_DBMODE4")
		)
		(pad "AK22" smd circle
			(at 5.199888 11.599926 180)
			(size 0.3556 0.3556)
			(layers "F.Cu" "F.Mask" "F.Paste")
			(net "SYS_ERROR1")
		)
		(pad "AK23" smd circle
			(at 5.999988 11.599926 180)
			(size 0.3556 0.3556)
			(layers "F.Cu" "F.Mask" "F.Paste")
			(net "SYS_HALT0#")
		)
		(pad "AK24" smd circle
			(at 6.800088 11.599926 180)
			(size 0.3556 0.3556)
			(layers "F.Cu" "F.Mask" "F.Paste")
			(net "SYS_DBMODE2")
		)
		(pad "AK25" smd circle
			(at 7.599934 11.599926 180)
			(size 0.3556 0.3556)
			(layers "F.Cu" "F.Mask" "F.Paste")
			(net "SPARE1")
		)
		(pad "AK26" smd circle
			(at 8.400034 11.599926 180)
			(size 0.3556 0.3556)
			(layers "F.Cu" "F.Mask" "F.Paste")
			(net "SYS_HALT1#")
		)
		(pad "AK27" smd circle
			(at 9.19988 11.599926 180)
			(size 0.3556 0.3556)
			(layers "F.Cu" "F.Mask" "F.Paste")
			(net "IOC_UART_0_TX")
		)
		(pad "AK28" smd circle
			(at 9.99998 11.599926 180)
			(size 0.4064 0.4064)
			(layers "F.Cu" "F.Mask" "F.Paste")
			(net "IOC_GPIO_19")
		)
		(pad "AK29" smd circle
			(at 10.80008 11.599926 180)
			(size 0.4064 0.4064)
			(layers "F.Cu" "F.Mask" "F.Paste")
			(net "IOC_GPIO_9")
		)
		(pad "B1" smd circle
			(at -11.599926 -10.80008 180)
			(size 0.4064 0.4064)
			(layers "F.Cu" "F.Mask" "F.Paste")
			(net "Net_1249")
		)
		(pad "B2" smd circle
			(at -10.80008 -10.80008 180)
			(size 0.4064 0.4064)
			(layers "F.Cu" "F.Mask" "F.Paste")
			(net "GND")
		)
		(pad "B3" smd circle
			(at -9.99998 -10.80008 180)
			(size 0.4064 0.4064)
			(layers "F.Cu" "F.Mask" "F.Paste")
			(net "Net_1215")
		)
		(pad "B4" smd circle
			(at -9.19988 -10.80008 180)
			(size 0.3556 0.3556)
			(layers "F.Cu" "F.Mask" "F.Paste")
			(net "Net_1216")
		)
		(pad "B5" smd circle
			(at -8.400034 -10.80008 180)
			(size 0.3556 0.3556)
			(layers "F.Cu" "F.Mask" "F.Paste")
			(net "Net_1217")
		)
		(pad "B6" smd circle
			(at -7.599934 -10.80008 180)
			(size 0.3556 0.3556)
			(layers "F.Cu" "F.Mask" "F.Paste")
			(net "GND")
		)
		(pad "B7" smd circle
			(at -6.800088 -10.80008 180)
			(size 0.3556 0.3556)
			(layers "F.Cu" "F.Mask" "F.Paste")
			(net "ICE1_TCK")
		)
		(pad "B8" smd circle
			(at -5.999988 -10.80008 180)
			(size 0.3556 0.3556)
			(layers "F.Cu" "F.Mask" "F.Paste")
			(net "ICE0_TDI")
		)
		(pad "B9" smd circle
			(at -5.199888 -10.80008 180)
			(size 0.3556 0.3556)
			(layers "F.Cu" "F.Mask" "F.Paste")
			(net "IOC_VREF_SET")
		)
		(pad "B10" smd circle
			(at -4.400042 -10.80008 180)
			(size 0.3556 0.3556)
			(layers "F.Cu" "F.Mask" "F.Paste")
			(net "Net_1218")
		)
		(pad "B11" smd circle
			(at -3.599942 -10.80008 180)
			(size 0.3556 0.3556)
			(layers "F.Cu" "F.Mask" "F.Paste")
			(net "GND")
		)
		(pad "B12" smd circle
			(at -2.800096 -10.80008 180)
			(size 0.3556 0.3556)
			(layers "F.Cu" "F.Mask" "F.Paste")
			(net "AVSO_IDDTN18")
		)
		(pad "B13" smd circle
			(at -1.999996 -10.80008 180)
			(size 0.3556 0.3556)
			(layers "F.Cu" "F.Mask" "F.Paste")
			(net "AVSO_VREF")
		)
		(pad "B14" smd circle
			(at -1.199896 -10.80008 180)
			(size 0.3556 0.3556)
			(layers "F.Cu" "F.Mask" "F.Paste")
			(net "GND")
		)
		(pad "B15" smd circle
			(at -0.40005 -10.80008 180)
			(size 0.3556 0.3556)
			(layers "F.Cu" "F.Mask" "F.Paste")
			(net "GND")
		)
		(pad "B16" smd circle
			(at 0.40005 -10.80008 180)
			(size 0.3556 0.3556)
			(layers "F.Cu" "F.Mask" "F.Paste")
			(net "LSI_JTAG_EN_N")
		)
		(pad "B17" smd circle
			(at 1.199896 -10.80008 180)
			(size 0.3556 0.3556)
			(layers "F.Cu" "F.Mask" "F.Paste")
			(net "LSI_SCAN_EN")
		)
		(pad "B18" smd circle
			(at 1.999996 -10.80008 180)
			(size 0.3556 0.3556)
			(layers "F.Cu" "F.Mask" "F.Paste")
			(net "JTAG_IOC_TMS")
		)
		(pad "B19" smd circle
			(at 2.800096 -10.80008 180)
			(size 0.3556 0.3556)
			(layers "F.Cu" "F.Mask" "F.Paste")
			(net "XM_CS0_N")
		)
		(pad "B20" smd circle
			(at 3.599942 -10.80008 180)
			(size 0.3556 0.3556)
			(layers "F.Cu" "F.Mask" "F.Paste")
			(net "XM_F_RST_N")
		)
		(pad "B21" smd circle
			(at 4.400042 -10.80008 180)
			(size 0.3556 0.3556)
			(layers "F.Cu" "F.Mask" "F.Paste")
			(net "XM_NAND_CS_N")
		)
	)
)
